(kicad_pcb
	(version 20241229)
	(generator "pcbnew")
	(generator_version "9.0")
	(general
		(thickness 1.294)
		(legacy_teardrops no)
	)
	(paper "A3")
	(title_block
		(title "Kintex 410T devboard")
		(date "2024-04-03")
		(rev "1.1.2")
		(comment 9 "footprint 170 of 975 (U1), pads 597-658 of 900")
	)
	(layers
		(0 "F.Cu" mixed)
		(4 "In1.Cu" power)
		(6 "In2.Cu" power)
		(8 "In3.Cu" mixed)
		(10 "In4.Cu" power)
		(12 "In5.Cu" mixed)
		(14 "In6.Cu" power)
		(16 "In7.Cu" mixed)
		(18 "In8.Cu" power)
		(2 "B.Cu" mixed)
		(9 "F.Adhes" user "F.Adhesive")
		(11 "B.Adhes" user "B.Adhesive")
		(13 "F.Paste" user)
		(15 "B.Paste" user)
		(5 "F.SilkS" user "F.Silkscreen")
		(7 "B.SilkS" user "B.Silkscreen")
		(1 "F.Mask" user)
		(3 "B.Mask" user)
		(17 "Dwgs.User" user "User.Drawings")
		(19 "Cmts.User" user "User.Comments")
		(21 "Eco1.User" user "User.Eco1")
		(23 "Eco2.User" user "User.Eco2")
		(25 "Edge.Cuts" user)
		(27 "Margin" user)
		(31 "F.CrtYd" user "F.Courtyard")
		(29 "B.CrtYd" user "B.Courtyard")
		(35 "F.Fab" user)
		(33 "B.Fab" user)
	)
	(footprint "antmicro-footprints:BGA-900_31x31mm_Layout30x30_P1x1mm_FFG900"
		(locked yes)
		(layer "F.Cu")
		(at 200 130)
		(property "Reference" "U1"
			(at -15.74 -15.78 0)
			(layer "F.SilkS")
			(effects
				(font
					(size 0.7 0.7)
					(thickness 0.15)
				)
				(justify left bottom)
			)
		)
		(property "Value" "XC7K410T-2FFG900I"
			(at -4.436 17.635 0)
			(layer "F.Fab")
			(effects
				(font
					(size 0.7 0.7)
					(thickness 0.15)
				)
				(justify left bottom)
			)
		)
		(property "Description" "FPGA, Kintex-7, MMCM, PLL, 350 I/O's, 710 MHz, 406720 Cells, 970 mV to 1.03 V, FCBGA-900"
			(at 0 0 0)
			(layer "F.Fab")
			(hide yes)
			(effects
				(font
					(size 1.27 1.27)
					(thickness 0.15)
				)
			)
		)
		(property "Author" "Antmicro"
			(at 0 0 0)
			(layer "F.Fab")
			(hide yes)
			(effects
				(font
					(size 1 1)
					(thickness 0.15)
				)
			)
		)
		(property "License" "Apache-2.0"
			(at 0 0 0)
			(layer "F.Fab")
			(hide yes)
			(effects
				(font
					(size 1 1)
					(thickness 0.15)
				)
			)
		)
		(property "MPN" "XC7K410T-2FFG900I"
			(at 0 0 0)
			(layer "F.Fab")
			(hide yes)
			(effects
				(font
					(size 1 1)
					(thickness 0.15)
				)
			)
		)
		(property "Manufacturer" "AMD-Xilinx"
			(at 0 0 0)
			(layer "F.Fab")
			(hide yes)
			(effects
				(font
					(size 1 1)
					(thickness 0.15)
				)
			)
		)
		(sheetname "FPGA supply")
		(sheetfile "fpga-supply.kicad_sch")
		(attr smd)
		(pad "K27" smd circle
			(at 11.5 -5.5)
			(size 0.5 0.5)
			(property pad_prop_bga)
			(layers "F.Cu" "F.Mask" "F.Paste")
			(net 1 "GND")
			(pinfunction "GND")
			(pintype "passive")
			(solder_mask_margin 0.02)
		)
		(pad "K28" smd circle
			(at 12.5 -5.5)
			(size 0.5 0.5)
			(property pad_prop_bga)
			(layers "F.Cu" "F.Mask" "F.Paste")
			(net 1258 "/USER_IO.A32")
			(pinfunction "IO_L13P_T2_MRCC_15")
			(pintype "bidirectional")
			(die_length 18.837)
			(solder_mask_margin 0.02)
		)
		(pad "K29" smd circle
			(at 13.5 -5.5)
			(size 0.5 0.5)
			(property pad_prop_bga)
			(layers "F.Cu" "F.Mask" "F.Paste")
			(net 1050 "unconnected-(U1B-IO_L13N_T2_MRCC_15-PadK29)")
			(pinfunction "IO_L13N_T2_MRCC_15")
			(pintype "bidirectional+no_connect")
			(die_length 18.782)
			(solder_mask_margin 0.02)
		)
		(pad "K30" smd circle
			(at 14.5 -5.5)
			(size 0.5 0.5)
			(property pad_prop_bga)
			(layers "F.Cu" "F.Mask" "F.Paste")
			(net 1237 "/USER_IO.A7")
			(pinfunction "IO_L9N_T1_DQS_AD11N_15")
			(pintype "bidirectional")
			(die_length 18.721)
			(solder_mask_margin 0.02)
		)
		(pad "L1" smd circle
			(at -14.5 -4.5)
			(size 0.5 0.5)
			(property pad_prop_bga)
			(layers "F.Cu" "F.Mask" "F.Paste")
			(net 1 "GND")
			(pinfunction "GND")
			(pintype "passive")
			(solder_mask_margin 0.02)
		)
		(pad "L2" smd circle
			(at -13.5 -4.5)
			(size 0.5 0.5)
			(property pad_prop_bga)
			(layers "F.Cu" "F.Mask" "F.Paste")
			(net 1 "GND")
			(pinfunction "GND")
			(pintype "passive")
			(solder_mask_margin 0.02)
		)
		(pad "L3" smd circle
			(at -12.5 -4.5)
			(size 0.5 0.5)
			(property pad_prop_bga)
			(layers "F.Cu" "F.Mask" "F.Paste")
			(net 63 "/FMC+ HSPC/GTX116.TX3_N")
			(pinfunction "MGTXTXN3_116")
			(pintype "bidirectional")
			(die_length 11.585)
			(solder_mask_margin 0.02)
		)
		(pad "L4" smd circle
			(at -11.5 -4.5)
			(size 0.5 0.5)
			(property pad_prop_bga)
			(layers "F.Cu" "F.Mask" "F.Paste")
			(net 61 "/FMC+ HSPC/GTX116.TX3_P")
			(pinfunction "MGTXTXP3_116")
			(pintype "bidirectional")
			(die_length 11.561)
			(solder_mask_margin 0.02)
		)
		(pad "L5" smd circle
			(at -10.5 -4.5)
			(size 0.5 0.5)
			(property pad_prop_bga)
			(layers "F.Cu" "F.Mask" "F.Paste")
			(net 8 "+1V2_MGTAVTT")
			(pinfunction "MGTAVTT")
			(pintype "passive")
			(solder_mask_margin 0.02)
		)
		(pad "L6" smd circle
			(at -9.5 -4.5)
			(size 0.5 0.5)
			(property pad_prop_bga)
			(layers "F.Cu" "F.Mask" "F.Paste")
			(net 1 "GND")
			(pinfunction "GND")
			(pintype "passive")
			(solder_mask_margin 0.02)
		)
		(pad "L7" smd circle
			(at -8.5 -4.5)
			(size 0.5 0.5)
			(property pad_prop_bga)
			(layers "F.Cu" "F.Mask" "F.Paste")
			(net 596 "/FMC+ HSPC/GTX116.REFCLK0_N")
			(pinfunction "MGTREFCLK0N_116")
			(pintype "bidirectional")
			(die_length 8.449)
			(solder_mask_margin 0.02)
		)
		(pad "L8" smd circle
			(at -7.5 -4.5)
			(size 0.5 0.5)
			(property pad_prop_bga)
			(layers "F.Cu" "F.Mask" "F.Paste")
			(net 594 "/FMC+ HSPC/GTX116.REFCLK0_P")
			(pinfunction "MGTREFCLK0P_116")
			(pintype "bidirectional")
			(die_length 8.298)
			(solder_mask_margin 0.02)
		)
		(pad "L9" smd circle
			(at -6.5 -4.5)
			(size 0.5 0.5)
			(property pad_prop_bga)
			(layers "F.Cu" "F.Mask" "F.Paste")
			(net 1 "GND")
			(pinfunction "GND")
			(pintype "passive")
			(solder_mask_margin 0.02)
		)
		(pad "L10" smd circle
			(at -5.5 -4.5)
			(size 0.5 0.5)
			(property pad_prop_bga)
			(layers "F.Cu" "F.Mask" "F.Paste")
			(net 1051 "unconnected-(U1I-CFGBVS_0-PadL10)")
			(pinfunction "CFGBVS_0")
			(pintype "bidirectional+no_connect")
			(die_length 19.652)
			(solder_mask_margin 0.02)
		)
		(pad "L11" smd circle
			(at -4.5 -4.5)
			(size 0.5 0.5)
			(property pad_prop_bga)
			(layers "F.Cu" "F.Mask" "F.Paste")
			(net 405 "/FMC+ HSPC/FMC.IO6_P")
			(pinfunction "IO_L6P_T0_18")
			(pintype "bidirectional")
			(die_length 20.929)
			(solder_mask_margin 0.02)
		)
		(pad "L12" smd circle
			(at -3.5 -4.5)
			(size 0.5 0.5)
			(property pad_prop_bga)
			(layers "F.Cu" "F.Mask" "F.Paste")
			(net 449 "/FMC+ HSPC/FMC.IO3_P")
			(pinfunction "IO_L3P_T0_DQS_18")
			(pintype "bidirectional")
			(die_length 19.179)
			(solder_mask_margin 0.02)
		)
		(pad "L13" smd circle
			(at -2.5 -4.5)
			(size 0.5 0.5)
			(property pad_prop_bga)
			(layers "F.Cu" "F.Mask" "F.Paste")
			(net 446 "/FMC+ HSPC/FMC.IO3_N")
			(pinfunction "IO_L3N_T0_DQS_18")
			(pintype "bidirectional")
			(die_length 19.134)
			(solder_mask_margin 0.02)
		)
		(pad "L14" smd circle
			(at -1.5 -4.5)
			(size 0.5 0.5)
			(property pad_prop_bga)
			(layers "F.Cu" "F.Mask" "F.Paste")
			(net 1 "GND")
			(pinfunction "GND")
			(pintype "passive")
			(solder_mask_margin 0.02)
		)
		(pad "L15" smd circle
			(at -0.5 -4.5)
			(size 0.5 0.5)
			(property pad_prop_bga)
			(layers "F.Cu" "F.Mask" "F.Paste")
			(net 455 "/FMC+ HSPC/FMC.IO2_P")
			(pinfunction "IO_L2P_T0_18")
			(pintype "bidirectional")
			(die_length 17.689)
			(solder_mask_margin 0.02)
		)
		(pad "L16" smd circle
			(at 0.5 -4.5)
			(size 0.5 0.5)
			(property pad_prop_bga)
			(layers "F.Cu" "F.Mask" "F.Paste")
			(net 418 "/FMC+ HSPC/FMC.IO1_P")
			(pinfunction "IO_L1P_T0_18")
			(pintype "bidirectional")
			(die_length 18.303)
			(solder_mask_margin 0.02)
		)
		(pad "L17" smd circle
			(at 1.5 -4.5)
			(size 0.5 0.5)
			(property pad_prop_bga)
			(layers "F.Cu" "F.Mask" "F.Paste")
			(net 1056 "unconnected-(U1C-IO_L5P_T0_17-PadL17)")
			(pinfunction "IO_L5P_T0_17")
			(pintype "bidirectional+no_connect")
			(die_length 9.576)
			(solder_mask_margin 0.02)
		)
		(pad "L18" smd circle
			(at 2.5 -4.5)
			(size 0.5 0.5)
			(property pad_prop_bga)
			(layers "F.Cu" "F.Mask" "F.Paste")
			(net 1057 "unconnected-(U1C-IO_L5N_T0_17-PadL18)")
			(pinfunction "IO_L5N_T0_17")
			(pintype "bidirectional+no_connect")
			(die_length 8.081)
			(solder_mask_margin 0.02)
		)
		(pad "L19" smd circle
			(at 3.5 -4.5)
			(size 0.5 0.5)
			(property pad_prop_bga)
			(layers "F.Cu" "F.Mask" "F.Paste")
			(net 24 "+3V3")
			(pinfunction "VCCO_17")
			(pintype "passive")
			(solder_mask_margin 0.02)
		)
		(pad "L20" smd circle
			(at 4.5 -4.5)
			(size 0.5 0.5)
			(property pad_prop_bga)
			(layers "F.Cu" "F.Mask" "F.Paste")
			(net 1247 "/USER_IO.A18")
			(pinfunction "IO_L6N_T0_VREF_15")
			(pintype "bidirectional")
			(die_length 13.878)
			(solder_mask_margin 0.02)
		)
		(pad "L21" smd circle
			(at 5.5 -4.5)
			(size 0.5 0.5)
			(property pad_prop_bga)
			(layers "F.Cu" "F.Mask" "F.Paste")
			(net 1251 "/USER_IO.A25")
			(pinfunction "IO_L4P_T0_AD9P_15")
			(pintype "bidirectional")
			(die_length 11.376)
			(solder_mask_margin 0.02)
		)
		(pad "L22" smd circle
			(at 6.5 -4.5)
			(size 0.5 0.5)
			(property pad_prop_bga)
			(layers "F.Cu" "F.Mask" "F.Paste")
			(net 1193 "unconnected-(U1B-IO_L2P_T0_AD8P_15-PadL22)")
			(pinfunction "IO_L2P_T0_AD8P_15")
			(pintype "bidirectional+no_connect")
			(die_length 12.134)
			(solder_mask_margin 0.02)
		)
		(pad "L23" smd circle
			(at 7.5 -4.5)
			(size 0.5 0.5)
			(property pad_prop_bga)
			(layers "F.Cu" "F.Mask" "F.Paste")
			(net 1194 "unconnected-(U1B-IO_L2N_T0_AD8N_15-PadL23)")
			(pinfunction "IO_L2N_T0_AD8N_15")
			(pintype "bidirectional+no_connect")
			(die_length 12.328)
			(solder_mask_margin 0.02)
		)
		(pad "L24" smd circle
			(at 8.5 -4.5)
			(size 0.5 0.5)
			(property pad_prop_bga)
			(layers "F.Cu" "F.Mask" "F.Paste")
			(net 1 "GND")
			(pinfunction "GND")
			(pintype "passive")
			(solder_mask_margin 0.02)
		)
		(pad "L25" smd circle
			(at 9.5 -4.5)
			(size 0.5 0.5)
			(property pad_prop_bga)
			(layers "F.Cu" "F.Mask" "F.Paste")
			(net 1260 "/USER_IO.A35")
			(pinfunction "IO_L12P_T1_MRCC_AD5P_15")
			(pintype "bidirectional")
			(die_length 15.993)
			(solder_mask_margin 0.02)
		)
		(pad "L26" smd circle
			(at 10.5 -4.5)
			(size 0.5 0.5)
			(property pad_prop_bga)
			(layers "F.Cu" "F.Mask" "F.Paste")
			(net 1257 "/USER_IO.A31")
			(pinfunction "IO_L11P_T1_SRCC_AD12P_15")
			(pintype "bidirectional")
			(die_length 15.575)
			(solder_mask_margin 0.02)
		)
		(pad "L27" smd circle
			(at 11.5 -4.5)
			(size 0.5 0.5)
			(property pad_prop_bga)
			(layers "F.Cu" "F.Mask" "F.Paste")
			(net 1262 "/USER_IO.A37")
			(pinfunction "IO_L11N_T1_SRCC_AD12N_15")
			(pintype "bidirectional")
			(die_length 15.25)
			(solder_mask_margin 0.02)
		)
		(pad "L28" smd circle
			(at 12.5 -4.5)
			(size 0.5 0.5)
			(property pad_prop_bga)
			(layers "F.Cu" "F.Mask" "F.Paste")
			(net 1259 "/USER_IO.A33")
			(pinfunction "IO_L14N_T2_SRCC_15")
			(pintype "bidirectional")
			(die_length 15.833)
			(solder_mask_margin 0.02)
		)
		(pad "L29" smd circle
			(at 13.5 -4.5)
			(size 0.5 0.5)
			(property pad_prop_bga)
			(layers "F.Cu" "F.Mask" "F.Paste")
			(net 2 "VCC_USR_A")
			(pinfunction "VCCO_15")
			(pintype "passive")
			(solder_mask_margin 0.02)
		)
		(pad "L30" smd circle
			(at 14.5 -4.5)
			(size 0.5 0.5)
			(property pad_prop_bga)
			(layers "F.Cu" "F.Mask" "F.Paste")
			(net 1235 "/USER_IO.A3")
			(pinfunction "IO_L9P_T1_DQS_AD11P_15")
			(pintype "bidirectional")
			(die_length 18.142)
			(solder_mask_margin 0.02)
		)
		(pad "M1" smd circle
			(at -14.5 -3.5)
			(size 0.5 0.5)
			(property pad_prop_bga)
			(layers "F.Cu" "F.Mask" "F.Paste")
			(net 69 "/FMC+ HSPC/GTX116.TX2_N")
			(pinfunction "MGTXTXN2_116")
			(pintype "bidirectional")
			(die_length 13.468)
			(solder_mask_margin 0.02)
		)
		(pad "M2" smd circle
			(at -13.5 -3.5)
			(size 0.5 0.5)
			(property pad_prop_bga)
			(layers "F.Cu" "F.Mask" "F.Paste")
			(net 65 "/FMC+ HSPC/GTX116.TX2_P")
			(pinfunction "MGTXTXP2_116")
			(pintype "bidirectional")
			(die_length 13.415)
			(solder_mask_margin 0.02)
		)
		(pad "M3" smd circle
			(at -12.5 -3.5)
			(size 0.5 0.5)
			(property pad_prop_bga)
			(layers "F.Cu" "F.Mask" "F.Paste")
			(net 8 "+1V2_MGTAVTT")
			(pinfunction "MGTAVTT")
			(pintype "passive")
			(solder_mask_margin 0.02)
		)
		(pad "M4" smd circle
			(at -11.5 -3.5)
			(size 0.5 0.5)
			(property pad_prop_bga)
			(layers "F.Cu" "F.Mask" "F.Paste")
			(net 1 "GND")
			(pinfunction "GND")
			(pintype "passive")
			(solder_mask_margin 0.02)
		)
		(pad "M5" smd circle
			(at -10.5 -3.5)
			(size 0.5 0.5)
			(property pad_prop_bga)
			(layers "F.Cu" "F.Mask" "F.Paste")
			(net 283 "/FMC+ HSPC/GTX116.RX1_N")
			(pinfunction "MGTXRXN3_116")
			(pintype "bidirectional")
			(die_length 9.574)
			(solder_mask_margin 0.02)
		)
		(pad "M6" smd circle
			(at -9.5 -3.5)
			(size 0.5 0.5)
			(property pad_prop_bga)
			(layers "F.Cu" "F.Mask" "F.Paste")
			(net 288 "/FMC+ HSPC/GTX116.RX1_P")
			(pinfunction "MGTXRXP3_116")
			(pintype "bidirectional")
			(die_length 9.789)
			(solder_mask_margin 0.02)
		)
		(pad "M7" smd circle
			(at -8.5 -3.5)
			(size 0.5 0.5)
			(property pad_prop_bga)
			(layers "F.Cu" "F.Mask" "F.Paste")
			(net 6 "+1V0_MGTAVCC")
			(pinfunction "MGTAVCC")
			(pintype "passive")
			(solder_mask_margin 0.02)
		)
		(pad "M8" smd circle
			(at -7.5 -3.5)
			(size 0.5 0.5)
			(property pad_prop_bga)
			(layers "F.Cu" "F.Mask" "F.Paste")
			(net 1 "GND")
			(pinfunction "GND")
			(pintype "passive")
			(solder_mask_margin 0.02)
		)
		(pad "M9" smd circle
			(at -6.5 -3.5)
			(size 0.5 0.5)
			(property pad_prop_bga)
			(layers "F.Cu" "F.Mask" "F.Paste")
			(net 1 "GND")
			(pinfunction "GND")
			(pintype "passive")
			(solder_mask_margin 0.02)
		)
		(pad "M10" smd circle
			(at -5.5 -3.5)
			(size 0.5 0.5)
			(property pad_prop_bga)
			(layers "F.Cu" "F.Mask" "F.Paste")
			(net 246 "/FPGA Config/DONE")
			(pinfunction "DONE_0")
			(pintype "bidirectional")
			(die_length 19.51)
			(solder_mask_margin 0.02)
		)
		(pad "M11" smd circle
			(at -4.5 -3.5)
			(size 0.5 0.5)
			(property pad_prop_bga)
			(layers "F.Cu" "F.Mask" "F.Paste")
			(net 650 "+1V0")
			(pinfunction "VCCINT")
			(pintype "bidirectional")
			(solder_mask_margin 0.02)
		)
		(pad "M12" smd circle
			(at -3.5 -3.5)
			(size 0.5 0.5)
			(property pad_prop_bga)
			(layers "F.Cu" "F.Mask" "F.Paste")
			(net 1 "GND")
			(pinfunction "GND")
			(pintype "passive")
			(solder_mask_margin 0.02)
		)
		(pad "M13" smd circle
			(at -2.5 -3.5)
			(size 0.5 0.5)
			(property pad_prop_bga)
			(layers "F.Cu" "F.Mask" "F.Paste")
			(net 650 "+1V0")
			(pinfunction "VCCINT")
			(pintype "passive")
			(solder_mask_margin 0.02)
		)
		(pad "M14" smd circle
			(at -1.5 -3.5)
			(size 0.5 0.5)
			(property pad_prop_bga)
			(layers "F.Cu" "F.Mask" "F.Paste")
			(net 1 "GND")
			(pinfunction "GND")
			(pintype "passive")
			(solder_mask_margin 0.02)
		)
		(pad "M15" smd circle
			(at -0.5 -3.5)
			(size 0.5 0.5)
			(property pad_prop_bga)
			(layers "F.Cu" "F.Mask" "F.Paste")
			(net 650 "+1V0")
			(pinfunction "VCCINT")
			(pintype "passive")
			(solder_mask_margin 0.02)
		)
		(pad "M16" smd circle
			(at 0.5 -3.5)
			(size 0.5 0.5)
			(property pad_prop_bga)
			(layers "F.Cu" "F.Mask" "F.Paste")
			(net 1 "GND")
			(pinfunction "GND")
			(pintype "passive")
			(solder_mask_margin 0.02)
		)
		(pad "M17" smd circle
			(at 1.5 -3.5)
			(size 0.5 0.5)
			(property pad_prop_bga)
			(layers "F.Cu" "F.Mask" "F.Paste")
			(net 650 "+1V0")
			(pinfunction "VCCINT")
			(pintype "passive")
			(solder_mask_margin 0.02)
		)
		(pad "M18" smd circle
			(at 2.5 -3.5)
			(size 0.5 0.5)
			(property pad_prop_bga)
			(layers "F.Cu" "F.Mask" "F.Paste")
			(net 1 "GND")
			(pinfunction "GND")
			(pintype "passive")
			(solder_mask_margin 0.02)
		)
		(pad "M19" smd circle
			(at 3.5 -3.5)
			(size 0.5 0.5)
			(property pad_prop_bga)
			(layers "F.Cu" "F.Mask" "F.Paste")
			(net 1234 "/USER_IO.A1")
			(pinfunction "IO_0_15")
			(pintype "bidirectional")
			(die_length 10.051)
			(solder_mask_margin 0.02)
		)
		(pad "M20" smd circle
			(at 4.5 -3.5)
			(size 0.5 0.5)
			(property pad_prop_bga)
			(layers "F.Cu" "F.Mask" "F.Paste")
			(net 1245 "/USER_IO.A16")
			(pinfunction "IO_L6P_T0_15")
			(pintype "bidirectional")
			(die_length 12.146)
			(solder_mask_margin 0.02)
		)
		(pad "M21" smd circle
			(at 5.5 -3.5)
			(size 0.5 0.5)
			(property pad_prop_bga)
			(layers "F.Cu" "F.Mask" "F.Paste")
			(net 1 "GND")
			(pinfunction "GND")
			(pintype "passive")
			(solder_mask_margin 0.02)
		)
		(pad "M22" smd circle
			(at 6.5 -3.5)
			(size 0.5 0.5)
			(property pad_prop_bga)
			(layers "F.Cu" "F.Mask" "F.Paste")
			(net 1298 "unconnected-(U1B-IO_L24P_T3_RS1_15-PadM22)")
			(pinfunction "IO_L24P_T3_RS1_15")
			(pintype "bidirectional+no_connect")
			(die_length 14.019)
			(solder_mask_margin 0.02)
		)
		(pad "M23" smd circle
			(at 7.5 -3.5)
			(size 0.5 0.5)
			(property pad_prop_bga)
			(layers "F.Cu" "F.Mask" "F.Paste")
			(net 1255 "/USER_IO.A29")
			(pinfunction "IO_L24N_T3_RS0_15")
			(pintype "bidirectional")
			(die_length 12.184)
			(solder_mask_margin 0.02)
		)
		(pad "M24" smd circle
			(at 8.5 -3.5)
			(size 0.5 0.5)
			(property pad_prop_bga)
			(layers "F.Cu" "F.Mask" "F.Paste")
			(net 1333 "unconnected-(U1B-IO_L23P_T3_FOE_B_15-PadM24)")
			(pinfunction "IO_L23P_T3_FOE_B_15")
			(pintype "bidirectional+no_connect")
			(die_length 14.067)
			(solder_mask_margin 0.02)
		)
		(pad "M25" smd circle
			(at 9.5 -3.5)
			(size 0.5 0.5)
			(property pad_prop_bga)
			(layers "F.Cu" "F.Mask" "F.Paste")
			(net 1341 "unconnected-(U1B-IO_L23N_T3_FWE_B_15-PadM25)")
			(pinfunction "IO_L23N_T3_FWE_B_15")
			(pintype "bidirectional+no_connect")
			(die_length 13.167)
			(solder_mask_margin 0.02)
		)
		(pad "M26" smd circle
			(at 10.5 -3.5)
			(size 0.5 0.5)
			(property pad_prop_bga)
			(layers "F.Cu" "F.Mask" "F.Paste")
			(net 2 "VCC_USR_A")
			(pinfunction "VCCO_15")
			(pintype "passive")
			(solder_mask_margin 0.02)
		)
		(pad "M27" smd circle
			(at 11.5 -3.5)
			(size 0.5 0.5)
			(property pad_prop_bga)
			(layers "F.Cu" "F.Mask" "F.Paste")
			(net 1248 "/USER_IO.A21")
			(pinfunction "IO_L16N_T2_A27_15")
			(pintype "bidirectional")
			(die_length 14.949)
			(solder_mask_margin 0.02)
		)
		(pad "M28" smd circle
			(at 12.5 -3.5)
			(size 0.5 0.5)
			(property pad_prop_bga)
			(layers "F.Cu" "F.Mask" "F.Paste")
			(net 1239 "/USER_IO.A11")
			(pinfunction "IO_L14P_T2_SRCC_15")
			(pintype "bidirectional")
			(die_length 15.521)
			(solder_mask_margin 0.02)
		)
	)
)
